(kicad_pcb
	(version 20260206)
	(generator "pcbnew")
	(generator_version "10.0")
	(general
		(thickness 1.6)
		(legacy_teardrops no)
	)
	(paper "A4")
	(title_block
		(title "12092022_DA0F0TFB6D0_F0T_FAN_BOARD_MP5048_D_brd_v02_OCP.brd")
		(comment 1 "Grand Teton / footprints 566-571 of 924")
	)
	(layers
		(0 "F.Cu" signal "TOP")
		(4 "In1.Cu" signal "GND")
		(6 "In2.Cu" signal "IN1")
		(8 "In3.Cu" signal "IN2")
		(10 "In4.Cu" signal "GND1")
		(2 "B.Cu" signal "BOTTOM")
		(9 "F.Adhes" user "F.Adhesive")
		(11 "B.Adhes" user "B.Adhesive")
		(13 "F.Paste" user "Package Geometry/Pastemask Top")
		(15 "B.Paste" user "Package Geometry/Pastemask Bottom")
		(5 "F.SilkS" user "Ref Des/Silkscreen Top")
		(7 "B.SilkS" user "Ref Des/Silkscreen Bottom")
		(1 "F.Mask" user "Board Geometry/Soldermask Top")
		(3 "B.Mask" user "Board Geometry/Soldermask Bottom")
		(17 "Dwgs.User" user "User.Drawings")
		(19 "Cmts.User" user "User.Comments")
		(21 "Eco1.User" user "User.Eco1")
		(23 "Eco2.User" user "User.Eco2")
		(25 "Edge.Cuts" user "Board Geometry/Outline")
		(27 "Margin" user)
		(31 "F.CrtYd" user "Package Geometry/Place Bound Top")
		(29 "B.CrtYd" user "Package Geometry/Place Bound Bottom")
		(35 "F.Fab" user "Ref Des/Assembly Top")
		(33 "B.Fab" user "Ref Des/Assembly Bottom")
	)
	(footprint ""
		(layer "F.Cu")
		(at 18.415 -178.816 180)
		(property "Reference" "R5684"
			(at 0 0 180)
			(layer "F.SilkS")
			(hide yes)
			(effects
				(font
					(size 1.27 1.27)
				)
			)
		)
		(property "Value" ""
			(at 0 0 180)
			(layer "F.Fab")
			(effects
				(font
					(size 1.27 1.27)
				)
			)
		)
		(duplicate_pad_numbers_are_jumpers no)
		(fp_line
			(start 0.7874 0.4064)
			(end -0.7874 0.4064)
			(stroke
				(width 0.1524)
				(type default)
			)
			(layer "F.SilkS")
		)
		(fp_line
			(start 0.7874 -0.4064)
			(end 0.7874 0.4064)
			(stroke
				(width 0.1524)
				(type default)
			)
			(layer "F.SilkS")
		)
		(fp_line
			(start -0.7874 0.4064)
			(end -0.7874 -0.4064)
			(stroke
				(width 0.1524)
				(type default)
			)
			(layer "F.SilkS")
		)
		(fp_line
			(start -0.7874 -0.4064)
			(end 0.7874 -0.4064)
			(stroke
				(width 0.1524)
				(type default)
			)
			(layer "F.SilkS")
		)
		(fp_line
			(start 0.67945 0.3048)
			(end 0.120396 0.3048)
			(stroke
				(width 0.1)
				(type default)
			)
			(layer "F.Fab")
		)
		(fp_line
			(start 0.67945 -0.3048)
			(end 0.67945 0.3048)
			(stroke
				(width 0.1)
				(type default)
			)
			(layer "F.Fab")
		)
		(fp_line
			(start 0.12065 -0.2794)
			(end 0.12065 -0.3048)
			(stroke
				(width 0.1)
				(type default)
			)
			(layer "F.Fab")
		)
		(fp_line
			(start 0.12065 -0.3048)
			(end 0.67945 -0.3048)
			(stroke
				(width 0.1)
				(type default)
			)
			(layer "F.Fab")
		)
		(fp_line
			(start 0.120396 0.3048)
			(end 0.120396 0.2794)
			(stroke
				(width 0.1)
				(type default)
			)
			(layer "F.Fab")
		)
		(fp_line
			(start 0.120396 0.2794)
			(end -0.12065 0.2794)
			(stroke
				(width 0.1)
				(type default)
			)
			(layer "F.Fab")
		)
		(fp_line
			(start -0.12065 0.3048)
			(end -0.67945 0.3048)
			(stroke
				(width 0.1)
				(type default)
			)
			(layer "F.Fab")
		)
		(fp_line
			(start -0.12065 0.2794)
			(end -0.12065 0.3048)
			(stroke
				(width 0.1)
				(type default)
			)
			(layer "F.Fab")
		)
		(fp_line
			(start -0.12065 -0.2794)
			(end 0.12065 -0.2794)
			(stroke
				(width 0.1)
				(type default)
			)
			(layer "F.Fab")
		)
		(fp_line
			(start -0.12065 -0.305054)
			(end -0.12065 -0.2794)
			(stroke
				(width 0.1)
				(type default)
			)
			(layer "F.Fab")
		)
		(fp_line
			(start -0.67945 0.3048)
			(end -0.67945 -0.305054)
			(stroke
				(width 0.1)
				(type default)
			)
			(layer "F.Fab")
		)
		(fp_line
			(start -0.67945 -0.305054)
			(end -0.12065 -0.305054)
			(stroke
				(width 0.1)
				(type default)
			)
			(layer "F.Fab")
		)
		(pad "1" smd circle
			(at -0.40005 0 180)
			(size 0 0)
			(layers "F.Cu" "F.Mask" "F.Paste")
			(net "P3V3_AUX")
		)
		(pad "2" smd circle
			(at 0.40005 0 180)
			(size 0 0)
			(layers "F.Cu" "F.Mask" "F.Paste")
			(net "FM_BOARD_ID1")
		)
	)
	(footprint ""
		(layer "F.Cu")
		(at 37.465 -32.217868)
		(property "Reference" "R5236"
			(at 0 0 0)
			(layer "F.SilkS")
			(hide yes)
			(effects
				(font
					(size 1.27 1.27)
				)
			)
		)
		(property "Value" ""
			(at 0 0 0)
			(layer "F.Fab")
			(effects
				(font
					(size 1.27 1.27)
				)
			)
		)
		(duplicate_pad_numbers_are_jumpers no)
		(fp_line
			(start -0.7874 -0.4064)
			(end 0.7874 -0.4064)
			(stroke
				(width 0.1524)
				(type default)
			)
			(layer "F.SilkS")
		)
		(fp_line
			(start -0.7874 0.4064)
			(end -0.7874 -0.4064)
			(stroke
				(width 0.1524)
				(type default)
			)
			(layer "F.SilkS")
		)
		(fp_line
			(start 0.7874 -0.4064)
			(end 0.7874 0.4064)
			(stroke
				(width 0.1524)
				(type default)
			)
			(layer "F.SilkS")
		)
		(fp_line
			(start 0.7874 0.4064)
			(end -0.7874 0.4064)
			(stroke
				(width 0.1524)
				(type default)
			)
			(layer "F.SilkS")
		)
		(fp_line
			(start -0.67945 -0.305054)
			(end -0.12065 -0.305054)
			(stroke
				(width 0.1)
				(type default)
			)
			(layer "F.Fab")
		)
		(fp_line
			(start -0.67945 0.3048)
			(end -0.67945 -0.305054)
			(stroke
				(width 0.1)
				(type default)
			)
			(layer "F.Fab")
		)
		(fp_line
			(start -0.12065 -0.305054)
			(end -0.12065 -0.2794)
			(stroke
				(width 0.1)
				(type default)
			)
			(layer "F.Fab")
		)
		(fp_line
			(start -0.12065 -0.2794)
			(end 0.12065 -0.2794)
			(stroke
				(width 0.1)
				(type default)
			)
			(layer "F.Fab")
		)
		(fp_line
			(start -0.12065 0.2794)
			(end -0.12065 0.3048)
			(stroke
				(width 0.1)
				(type default)
			)
			(layer "F.Fab")
		)
		(fp_line
			(start -0.12065 0.3048)
			(end -0.67945 0.3048)
			(stroke
				(width 0.1)
				(type default)
			)
			(layer "F.Fab")
		)
		(fp_line
			(start 0.120396 0.2794)
			(end -0.12065 0.2794)
			(stroke
				(width 0.1)
				(type default)
			)
			(layer "F.Fab")
		)
		(fp_line
			(start 0.120396 0.3048)
			(end 0.120396 0.2794)
			(stroke
				(width 0.1)
				(type default)
			)
			(layer "F.Fab")
		)
		(fp_line
			(start 0.12065 -0.3048)
			(end 0.67945 -0.3048)
			(stroke
				(width 0.1)
				(type default)
			)
			(layer "F.Fab")
		)
		(fp_line
			(start 0.12065 -0.2794)
			(end 0.12065 -0.3048)
			(stroke
				(width 0.1)
				(type default)
			)
			(layer "F.Fab")
		)
		(fp_line
			(start 0.67945 -0.3048)
			(end 0.67945 0.3048)
			(stroke
				(width 0.1)
				(type default)
			)
			(layer "F.Fab")
		)
		(fp_line
			(start 0.67945 0.3048)
			(end 0.120396 0.3048)
			(stroke
				(width 0.1)
				(type default)
			)
			(layer "F.Fab")
		)
		(pad "1" smd circle
			(at -0.40005 0)
			(size 0 0)
			(layers "F.Cu" "F.Mask" "F.Paste")
			(net "FAN_3_PWM_OL")
		)
		(pad "2" smd circle
			(at 0.40005 0)
			(size 0 0)
			(layers "F.Cu" "F.Mask" "F.Paste")
			(net "FAN_3_PWM_OL_R")
		)
	)
	(footprint ""
		(layer "F.Cu")
		(at 36.322 -101.784912)
		(property "Reference" "D277"
			(at -0.889 1.532382 0)
			(unlocked yes)
			(layer "F.SilkS")
			(effects
				(font
					(size 0.7874 0.5842)
					(thickness 0.1524)
				)
				(justify left)
			)
		)
		(property "Value" ""
			(at 0 0 0)
			(layer "F.Fab")
			(effects
				(font
					(size 1.27 1.27)
				)
			)
		)
		(duplicate_pad_numbers_are_jumpers no)
		(fp_line
			(start -0.854964 -0.450088)
			(end -0.854964 0.450088)
			(stroke
				(width 0.1524)
				(type default)
			)
			(layer "F.SilkS")
		)
		(fp_line
			(start -0.854964 0.450088)
			(end 0.925068 0.450088)
			(stroke
				(width 0.1524)
				(type default)
			)
			(layer "F.SilkS")
		)
		(fp_line
			(start 0.845058 0.4064)
			(end 0.845058 -0.381)
			(stroke
				(width 0.1524)
				(type default)
			)
			(layer "F.SilkS")
		)
		(fp_line
			(start 0.870458 -0.2794)
			(end 0.845058 0.4064)
			(stroke
				(width 0.1524)
				(type default)
			)
			(layer "F.SilkS")
		)
		(fp_line
			(start 0.94488 -0.450088)
			(end -0.854964 -0.450088)
			(stroke
				(width 0.1524)
				(type default)
			)
			(layer "F.SilkS")
		)
		(fp_line
			(start 0.94488 0.450088)
			(end 0.94488 -0.450088)
			(stroke
				(width 0.1524)
				(type default)
			)
			(layer "F.SilkS")
		)
		(fp_line
			(start -0.54991 -0.350012)
			(end -0.54991 0.350012)
			(stroke
				(width 0.1)
				(type default)
			)
			(layer "F.Fab")
		)
		(fp_line
			(start -0.54991 0.350012)
			(end 0.54991 0.350012)
			(stroke
				(width 0.1)
				(type default)
			)
			(layer "F.Fab")
		)
		(fp_line
			(start 0.54991 -0.350012)
			(end -0.54991 -0.350012)
			(stroke
				(width 0.1)
				(type default)
			)
			(layer "F.Fab")
		)
		(fp_line
			(start 0.54991 0.350012)
			(end 0.54991 -0.350012)
			(stroke
				(width 0.1)
				(type default)
			)
			(layer "F.Fab")
		)
		(fp_text user "+"
			(at -0.762 1.042162 180)
			(unlocked yes)
			(layer "F.SilkS")
			(effects
				(font
					(size 1.905 1.4224)
					(thickness 0.1524)
				)
				(justify left)
			)
		)
		(fp_text user "-"
			(at 2.286 0.407162 180)
			(unlocked yes)
			(layer "F.SilkS")
			(effects
				(font
					(size 1.905 1.4224)
					(thickness 0.1524)
				)
				(justify left)
			)
		)
		(fp_text user "+"
			(at -0.808228 0.239014 180)
			(unlocked yes)
			(layer "F.Fab")
			(effects
				(font
					(size 1.905 1.4224)
					(thickness 0.1524)
				)
				(justify left)
			)
		)
		(fp_text user "-"
			(at 2.48539 0.239014 180)
			(unlocked yes)
			(layer "F.Fab")
			(effects
				(font
					(size 1.905 1.4224)
					(thickness 0.1524)
				)
				(justify left)
			)
		)
		(pad "A" smd rect
			(at -0.424942 0)
			(size 0.5588 0.6096)
			(layers "F.Cu" "F.Mask" "F.Paste")
			(net "GND")
		)
		(pad "C" smd rect
			(at 0.424942 0 180)
			(size 0.5588 0.6096)
			(layers "F.Cu" "F.Mask" "F.Paste")
			(net "FAN_2_TACH_OL_D")
		)
	)
	(footprint ""
		(layer "F.Cu")
		(at 31.115 -27.432 90)
		(property "Reference" "R5324"
			(at 0 0 90)
			(layer "F.SilkS")
			(hide yes)
			(effects
				(font
					(size 1.27 1.27)
				)
			)
		)
		(property "Value" ""
			(at 0 0 90)
			(layer "F.Fab")
			(effects
				(font
					(size 1.27 1.27)
				)
			)
		)
		(duplicate_pad_numbers_are_jumpers no)
		(fp_line
			(start 1.2954 -0.5842)
			(end 1.2954 0.5842)
			(stroke
				(width 0.1524)
				(type default)
			)
			(layer "F.SilkS")
		)
		(fp_line
			(start -1.2954 -0.5842)
			(end 1.2954 -0.5842)
			(stroke
				(width 0.1524)
				(type default)
			)
			(layer "F.SilkS")
		)
		(fp_line
			(start 1.2954 0.5842)
			(end -1.2954 0.5842)
			(stroke
				(width 0.1524)
				(type default)
			)
			(layer "F.SilkS")
		)
		(fp_line
			(start -1.2954 0.5842)
			(end -1.2954 -0.5842)
			(stroke
				(width 0.1524)
				(type default)
			)
			(layer "F.SilkS")
		)
		(fp_line
			(start 0.8636 -0.4572)
			(end 0.8636 -0.406654)
			(stroke
				(width 0.1)
				(type default)
			)
			(layer "F.Fab")
		)
		(fp_line
			(start -0.8636 -0.4572)
			(end 0.8636 -0.4572)
			(stroke
				(width 0.1)
				(type default)
			)
			(layer "F.Fab")
		)
		(fp_line
			(start 1.1938 -0.406654)
			(end 1.1938 0.4064)
			(stroke
				(width 0.1)
				(type default)
			)
			(layer "F.Fab")
		)
		(fp_line
			(start 0.8636 -0.406654)
			(end 1.1938 -0.406654)
			(stroke
				(width 0.1)
				(type default)
			)
			(layer "F.Fab")
		)
		(fp_line
			(start -0.8636 -0.406654)
			(end -0.8636 -0.4572)
			(stroke
				(width 0.1)
				(type default)
			)
			(layer "F.Fab")
		)
		(fp_line
			(start -1.1938 -0.406654)
			(end -0.8636 -0.406654)
			(stroke
				(width 0.1)
				(type default)
			)
			(layer "F.Fab")
		)
		(fp_line
			(start 1.1938 0.4064)
			(end 0.8636 0.4064)
			(stroke
				(width 0.1)
				(type default)
			)
			(layer "F.Fab")
		)
		(fp_line
			(start 0.8636 0.4064)
			(end 0.8636 0.4572)
			(stroke
				(width 0.1)
				(type default)
			)
			(layer "F.Fab")
		)
		(fp_line
			(start -0.8636 0.4064)
			(end -1.1938 0.4064)
			(stroke
				(width 0.1)
				(type default)
			)
			(layer "F.Fab")
		)
		(fp_line
			(start -1.1938 0.4064)
			(end -1.1938 -0.406654)
			(stroke
				(width 0.1)
				(type default)
			)
			(layer "F.Fab")
		)
		(fp_line
			(start -0.8636 0.4318)
			(end -0.8636 0.4064)
			(stroke
				(width 0.1)
				(type default)
			)
			(layer "F.Fab")
		)
		(fp_line
			(start 0.8636 0.4572)
			(end -0.8636 0.4572)
			(stroke
				(width 0.1)
				(type default)
			)
			(layer "F.Fab")
		)
		(fp_line
			(start -0.8636 0.4572)
			(end -0.8636 0.4318)
			(stroke
				(width 0.1)
				(type default)
			)
			(layer "F.Fab")
		)
		(pad "1" smd rect
			(at -0.7366 0)
			(size 0.7112 0.8128)
			(layers "F.Cu" "F.Mask" "F.Paste")
			(net "P52V_FAN_3")
		)
		(pad "2" smd rect
			(at 0.7366 0)
			(size 0.7112 0.8128)
			(layers "F.Cu" "F.Mask" "F.Paste")
			(net "FAN_3_TACH_IL_R")
		)
	)
	(footprint ""
		(layer "F.Cu")
		(at 18.669 -199.037956 180)
		(property "Reference" "D256"
			(at 1.524 1.087374 0)
			(unlocked yes)
			(layer "F.SilkS")
			(effects
				(font
					(size 0.7874 0.5842)
					(thickness 0.1524)
				)
				(justify left)
			)
		)
		(property "Value" ""
			(at 0 0 180)
			(layer "F.Fab")
			(effects
				(font
					(size 1.27 1.27)
				)
			)
		)
		(duplicate_pad_numbers_are_jumpers no)
		(fp_line
			(start 0.94488 0.450088)
			(end 0.94488 -0.450088)
			(stroke
				(width 0.1524)
				(type default)
			)
			(layer "F.SilkS")
		)
		(fp_line
			(start 0.94488 -0.450088)
			(end -0.854964 -0.450088)
			(stroke
				(width 0.1524)
				(type default)
			)
			(layer "F.SilkS")
		)
		(fp_line
			(start 0.870458 -0.2794)
			(end 0.845058 0.4064)
			(stroke
				(width 0.1524)
				(type default)
			)
			(layer "F.SilkS")
		)
		(fp_line
			(start 0.845058 0.4064)
			(end 0.845058 -0.381)
			(stroke
				(width 0.1524)
				(type default)
			)
			(layer "F.SilkS")
		)
		(fp_line
			(start -0.854964 0.450088)
			(end 0.925068 0.450088)
			(stroke
				(width 0.1524)
				(type default)
			)
			(layer "F.SilkS")
		)
		(fp_line
			(start -0.854964 -0.450088)
			(end -0.854964 0.450088)
			(stroke
				(width 0.1524)
				(type default)
			)
			(layer "F.SilkS")
		)
		(fp_line
			(start 0.54991 0.350012)
			(end 0.54991 -0.350012)
			(stroke
				(width 0.1)
				(type default)
			)
			(layer "F.Fab")
		)
		(fp_line
			(start 0.54991 -0.350012)
			(end -0.54991 -0.350012)
			(stroke
				(width 0.1)
				(type default)
			)
			(layer "F.Fab")
		)
		(fp_line
			(start -0.54991 0.350012)
			(end 0.54991 0.350012)
			(stroke
				(width 0.1)
				(type default)
			)
			(layer "F.Fab")
		)
		(fp_line
			(start -0.54991 -0.350012)
			(end -0.54991 0.350012)
			(stroke
				(width 0.1)
				(type default)
			)
			(layer "F.Fab")
		)
		(fp_text user "-"
			(at 2.032 -0.441706 0)
			(unlocked yes)
			(layer "F.SilkS")
			(effects
				(font
					(size 1.905 1.4224)
					(thickness 0.1524)
				)
				(justify left)
			)
		)
		(fp_text user "+"
			(at -0.8636 0.396494 0)
			(unlocked yes)
			(layer "F.SilkS")
			(effects
				(font
					(size 1.905 1.4224)
					(thickness 0.1524)
				)
				(justify left)
			)
		)
		(fp_text user "-"
			(at 2.48539 0.239014 0)
			(unlocked yes)
			(layer "F.Fab")
			(effects
				(font
					(size 1.905 1.4224)
					(thickness 0.1524)
				)
				(justify left)
			)
		)
		(fp_text user "+"
			(at -0.808228 0.239014 0)
			(unlocked yes)
			(layer "F.Fab")
			(effects
				(font
					(size 1.905 1.4224)
					(thickness 0.1524)
				)
				(justify left)
			)
		)
		(pad "A" smd rect
			(at -0.424942 0 180)
			(size 0.5588 0.6096)
			(layers "F.Cu" "F.Mask" "F.Paste")
			(net "GND")
		)
		(pad "C" smd rect
			(at 0.424942 0)
			(size 0.5588 0.6096)
			(layers "F.Cu" "F.Mask" "F.Paste")
			(net "FAN_6_PWM_IL_R")
		)
	)
	(footprint ""
		(layer "F.Cu")
		(at 25.654 -143.891 -90)
		(property "Reference" "R4786"
			(at 0 0 270)
			(layer "F.SilkS")
			(hide yes)
			(effects
				(font
					(size 1.27 1.27)
				)
			)
		)
		(property "Value" ""
			(at 0 0 270)
			(layer "F.Fab")
			(effects
				(font
					(size 1.27 1.27)
				)
			)
		)
		(duplicate_pad_numbers_are_jumpers no)
		(fp_line
			(start -0.7874 0.4064)
			(end -0.7874 -0.4064)
			(stroke
				(width 0.1524)
				(type default)
			)
			(layer "F.SilkS")
		)
		(fp_line
			(start 0.7874 0.4064)
			(end -0.7874 0.4064)
			(stroke
				(width 0.1524)
				(type default)
			)
			(layer "F.SilkS")
		)
		(fp_line
			(start -0.7874 -0.4064)
			(end 0.7874 -0.4064)
			(stroke
				(width 0.1524)
				(type default)
			)
			(layer "F.SilkS")
		)
		(fp_line
			(start 0.7874 -0.4064)
			(end 0.7874 0.4064)
			(stroke
				(width 0.1524)
				(type default)
			)
			(layer "F.SilkS")
		)
		(fp_line
			(start -0.67945 0.3048)
			(end -0.67945 -0.305054)
			(stroke
				(width 0.1)
				(type default)
			)
			(layer "F.Fab")
		)
		(fp_line
			(start -0.12065 0.3048)
			(end -0.67945 0.3048)
			(stroke
				(width 0.1)
				(type default)
			)
			(layer "F.Fab")
		)
		(fp_line
			(start 0.120396 0.3048)
			(end 0.120396 0.2794)
			(stroke
				(width 0.1)
				(type default)
			)
			(layer "F.Fab")
		)
		(fp_line
			(start 0.67945 0.3048)
			(end 0.120396 0.3048)
			(stroke
				(width 0.1)
				(type default)
			)
			(layer "F.Fab")
		)
		(fp_line
			(start -0.12065 0.2794)
			(end -0.12065 0.3048)
			(stroke
				(width 0.1)
				(type default)
			)
			(layer "F.Fab")
		)
		(fp_line
			(start 0.120396 0.2794)
			(end -0.12065 0.2794)
			(stroke
				(width 0.1)
				(type default)
			)
			(layer "F.Fab")
		)
		(fp_line
			(start -0.12065 -0.2794)
			(end 0.12065 -0.2794)
			(stroke
				(width 0.1)
				(type default)
			)
			(layer "F.Fab")
		)
		(fp_line
			(start 0.12065 -0.2794)
			(end 0.12065 -0.3048)
			(stroke
				(width 0.1)
				(type default)
			)
			(layer "F.Fab")
		)
		(fp_line
			(start 0.12065 -0.3048)
			(end 0.67945 -0.3048)
			(stroke
				(width 0.1)
				(type default)
			)
			(layer "F.Fab")
		)
		(fp_line
			(start 0.67945 -0.3048)
			(end 0.67945 0.3048)
			(stroke
				(width 0.1)
				(type default)
			)
			(layer "F.Fab")
		)
		(fp_line
			(start -0.67945 -0.305054)
			(end -0.12065 -0.305054)
			(stroke
				(width 0.1)
				(type default)
			)
			(layer "F.Fab")
		)
		(fp_line
			(start -0.12065 -0.305054)
			(end -0.12065 -0.2794)
			(stroke
				(width 0.1)
				(type default)
			)
			(layer "F.Fab")
		)
		(pad "1" smd circle
			(at -0.40005 0 270)
			(size 0 0)
			(layers "F.Cu" "F.Mask" "F.Paste")
			(net "SMB_FAN1_R_SDA")
		)
		(pad "2" smd circle
			(at 0.40005 0 270)
			(size 0 0)
			(layers "F.Cu" "F.Mask" "F.Paste")
			(net "SMB_FAN1_SDA")
		)
	)
)
